# S9S_MB_2U (Grand Teton) — schematic netlist excerpt (pin names and nets, part order shuffled) for the footprints in the layout excerpt that follows; sources: Cadence DE-HDL packaged netlist, KiCad conversion of 03242023_DA0F0TMBIJ0_F0T_Motherboard_J_brd_V01_OCP.brd

R2524  Q_RES  1K 1% CHIP  pkg 0402LF  page 284 : A = P3V3_AUX ; B = PVCCIN_CPU1_VR_FAULT
PC1229  Q_CAPP  330UF 2V 35% SPCAP  pkg SMLF  page 262 : A = P1V05_PCH_AUX ; B = GND

(kicad_pcb
	(version 20260206)
	(generator "pcbnew")
	(generator_version "10.0")
	(general
		(thickness 1.6)
		(legacy_teardrops no)
	)
	(paper "A4")
	(title_block
		(title "03242023_DA0F0TMBIJ0_F0T_Motherboard_J_brd_V01_OCP.brd")
		(comment 1 "Grand Teton / footprints 4519-4520 of 6105")
	)
	(layers
		(0 "F.Cu" signal "TOP")
		(4 "In1.Cu" signal "GND")
		(6 "In2.Cu" signal "IN1")
		(8 "In3.Cu" signal "GND1")
		(10 "In4.Cu" signal "IN2")
		(12 "In5.Cu" signal "GND2")
		(14 "In6.Cu" signal "IN3")
		(16 "In7.Cu" signal "GND3")
		(18 "In8.Cu" signal "VCC")
		(20 "In9.Cu" signal "VCC1")
		(22 "In10.Cu" signal "GND4")
		(24 "In11.Cu" signal "IN4")
		(26 "In12.Cu" signal "GND5")
		(28 "In13.Cu" signal "IN5")
		(30 "In14.Cu" signal "GND6")
		(32 "In15.Cu" signal "IN6")
		(34 "In16.Cu" signal "GND7")
		(2 "B.Cu" signal "BOTTOM")
		(9 "F.Adhes" user "F.Adhesive")
		(11 "B.Adhes" user "B.Adhesive")
		(13 "F.Paste" user "Package Geometry/Pastemask Top")
		(15 "B.Paste" user "Package Geometry/Pastemask Bottom")
		(5 "F.SilkS" user "Ref Des/Silkscreen Top")
		(7 "B.SilkS" user "Ref Des/Silkscreen Bottom")
		(1 "F.Mask" user "Board Geometry/Soldermask Top")
		(3 "B.Mask" user "Board Geometry/Soldermask Bottom")
		(17 "Dwgs.User" user "User.Drawings")
		(19 "Cmts.User" user "User.Comments")
		(21 "Eco1.User" user "User.Eco1")
		(23 "Eco2.User" user "User.Eco2")
		(25 "Edge.Cuts" user "Board Geometry/Outline")
		(27 "Margin" user)
		(31 "F.CrtYd" user "Package Geometry/Place Bound Top")
		(29 "B.CrtYd" user "Package Geometry/Place Bound Bottom")
		(35 "F.Fab" user "Ref Des/Assembly Top")
		(33 "B.Fab" user "Ref Des/Assembly Bottom")
	)
	(footprint ""
		(layer "B.Cu")
		(at 269.179294 -64.432434)
		(property "Reference" "PC1229"
			(at 0 0 0)
			(layer "B.SilkS")
			(hide yes)
			(effects
				(font
					(size 1.27 1.27)
				)
				(justify mirror)
			)
		)
		(property "Value" ""
			(at 0 0 0)
			(layer "B.Fab")
			(effects
				(font
					(size 1.27 1.27)
				)
				(justify mirror)
			)
		)
		(duplicate_pad_numbers_are_jumpers no)
		(fp_line
			(start -4.53898 -2.15011)
			(end -4.53898 2.15011)
			(stroke
				(width 0.1524)
				(type default)
			)
			(layer "B.SilkS")
		)
		(fp_line
			(start -4.53898 2.15011)
			(end 4.53898 2.15011)
			(stroke
				(width 0.1524)
				(type default)
			)
			(layer "B.SilkS")
		)
		(fp_line
			(start 4.53898 -2.150618)
			(end 4.539742 2.152142)
			(stroke
				(width 0.1524)
				(type default)
			)
			(layer "B.SilkS")
		)
		(fp_line
			(start 4.53898 -2.15011)
			(end -4.53898 -2.15011)
			(stroke
				(width 0.1524)
				(type default)
			)
			(layer "B.SilkS")
		)
		(fp_line
			(start 4.53898 2.15011)
			(end 4.53898 -2.15011)
			(stroke
				(width 0.1524)
				(type default)
			)
			(layer "B.SilkS")
		)
		(fp_line
			(start 4.69138 -2.150618)
			(end 4.692396 2.161032)
			(stroke
				(width 0.1524)
				(type default)
			)
			(layer "B.SilkS")
		)
		(fp_line
			(start 4.83108 2.150364)
			(end 4.447794 2.149348)
			(stroke
				(width 0.1524)
				(type default)
			)
			(layer "B.SilkS")
		)
		(fp_line
			(start 4.84378 -2.150618)
			(end 4.53898 -2.150618)
			(stroke
				(width 0.1524)
				(type default)
			)
			(layer "B.SilkS")
		)
		(fp_line
			(start 4.84378 -2.150618)
			(end 4.842256 2.163064)
			(stroke
				(width 0.1524)
				(type default)
			)
			(layer "B.SilkS")
		)
		(fp_line
			(start -3.64998 -2.15011)
			(end -3.64998 2.15011)
			(stroke
				(width 0.1)
				(type default)
			)
			(layer "B.Fab")
		)
		(fp_line
			(start -3.64998 2.15011)
			(end 3.64998 2.15011)
			(stroke
				(width 0.1)
				(type default)
			)
			(layer "B.Fab")
		)
		(fp_line
			(start 3.64998 -2.15011)
			(end -3.64998 -2.15011)
			(stroke
				(width 0.1)
				(type default)
			)
			(layer "B.Fab")
		)
		(fp_line
			(start 3.64998 2.15011)
			(end 3.64998 -2.15011)
			(stroke
				(width 0.1)
				(type default)
			)
			(layer "B.Fab")
		)
		(fp_text user "-"
			(at -4.658614 2.955036 0)
			(unlocked yes)
			(layer "B.SilkS")
			(effects
				(font
					(size 1.905 1.4224)
					(thickness 0.1524)
				)
				(justify left mirror)
			)
		)
		(fp_text user "+"
			(at 6.214872 -0.337058 0)
			(unlocked yes)
			(layer "B.SilkS")
			(effects
				(font
					(size 1.905 1.4224)
					(thickness 0.1524)
				)
				(justify left mirror)
			)
		)
		(fp_text user "-"
			(at -4.313174 -0.094488 0)
			(unlocked yes)
			(layer "B.Fab")
			(effects
				(font
					(size 1.905 1.4224)
					(thickness 0.1524)
				)
				(justify left mirror)
			)
		)
		(fp_text user "+"
			(at 6.214872 -0.337058 0)
			(unlocked yes)
			(layer "B.Fab")
			(effects
				(font
					(size 1.905 1.4224)
					(thickness 0.1524)
				)
				(justify left mirror)
			)
		)
		(pad "1" smd rect
			(at 3.199892 0 180)
			(size 2.413 2.8194)
			(layers "B.Cu" "B.Mask" "B.Paste")
			(net "P1V05_PCH_AUX")
		)
		(pad "2" smd rect
			(at -3.199892 0 180)
			(size 2.413 2.8194)
			(layers "B.Cu" "B.Mask" "B.Paste")
			(net "GND")
		)
	)
	(footprint ""
		(layer "B.Cu")
		(at 115.66652 -355.925628)
		(property "Reference" "R2524"
			(at 0 0 0)
			(layer "B.SilkS")
			(hide yes)
			(effects
				(font
					(size 1.27 1.27)
				)
				(justify mirror)
			)
		)
		(property "Value" ""
			(at 0 0 0)
			(layer "B.Fab")
			(effects
				(font
					(size 1.27 1.27)
				)
				(justify mirror)
			)
		)
		(duplicate_pad_numbers_are_jumpers no)
		(fp_line
			(start -0.7874 -0.4064)
			(end -0.7874 0.4064)
			(stroke
				(width 0.1524)
				(type default)
			)
			(layer "B.SilkS")
		)
		(fp_line
			(start -0.7874 0.4064)
			(end 0.7874 0.4064)
			(stroke
				(width 0.1524)
				(type default)
			)
			(layer "B.SilkS")
		)
		(fp_line
			(start 0.7874 -0.4064)
			(end -0.7874 -0.4064)
			(stroke
				(width 0.1524)
				(type default)
			)
			(layer "B.SilkS")
		)
		(fp_line
			(start 0.7874 0.4064)
			(end 0.7874 -0.4064)
			(stroke
				(width 0.1524)
				(type default)
			)
			(layer "B.SilkS")
		)
		(fp_line
			(start -0.67945 -0.3048)
			(end -0.67945 0.3048)
			(stroke
				(width 0.1)
				(type default)
			)
			(layer "B.Fab")
		)
		(fp_line
			(start -0.67945 0.3048)
			(end -0.120396 0.3048)
			(stroke
				(width 0.1)
				(type default)
			)
			(layer "B.Fab")
		)
		(fp_line
			(start -0.12065 -0.3048)
			(end -0.67945 -0.3048)
			(stroke
				(width 0.1)
				(type default)
			)
			(layer "B.Fab")
		)
		(fp_line
			(start -0.12065 -0.2794)
			(end -0.12065 -0.3048)
			(stroke
				(width 0.1)
				(type default)
			)
			(layer "B.Fab")
		)
		(fp_line
			(start -0.120396 0.2794)
			(end 0.12065 0.2794)
			(stroke
				(width 0.1)
				(type default)
			)
			(layer "B.Fab")
		)
		(fp_line
			(start -0.120396 0.3048)
			(end -0.120396 0.2794)
			(stroke
				(width 0.1)
				(type default)
			)
			(layer "B.Fab")
		)
		(fp_line
			(start 0.12065 -0.305054)
			(end 0.12065 -0.2794)
			(stroke
				(width 0.1)
				(type default)
			)
			(layer "B.Fab")
		)
		(fp_line
			(start 0.12065 -0.2794)
			(end -0.12065 -0.2794)
			(stroke
				(width 0.1)
				(type default)
			)
			(layer "B.Fab")
		)
		(fp_line
			(start 0.12065 0.2794)
			(end 0.12065 0.3048)
			(stroke
				(width 0.1)
				(type default)
			)
			(layer "B.Fab")
		)
		(fp_line
			(start 0.12065 0.3048)
			(end 0.67945 0.3048)
			(stroke
				(width 0.1)
				(type default)
			)
			(layer "B.Fab")
		)
		(fp_line
			(start 0.67945 -0.305054)
			(end 0.12065 -0.305054)
			(stroke
				(width 0.1)
				(type default)
			)
			(layer "B.Fab")
		)
		(fp_line
			(start 0.67945 0.3048)
			(end 0.67945 -0.305054)
			(stroke
				(width 0.1)
				(type default)
			)
			(layer "B.Fab")
		)
		(pad "1" smd circle
			(at 0.40005 0 180)
			(size 0 0)
			(layers "B.Cu" "B.Mask" "B.Paste")
			(net "P3V3_AUX")
		)
		(pad "2" smd circle
			(at -0.40005 0 180)
			(size 0 0)
			(layers "B.Cu" "B.Mask" "B.Paste")
			(net "PVCCIN_CPU1_VR_FAULT")
		)
	)
)
